(kicad_pcb
	(version 20260206)
	(generator "pcbnew")
	(generator_version "10.0")
	(general
		(thickness 1.6)
		(legacy_teardrops no)
	)
	(paper "A4")
	(title_block
		(title "netronome-mezz — pcbd0082-001_rev01_jul9_a.brd")
		(comment 1 "Open CloudServer (Microsoft) / footprints 593-602 of 714")
	)
	(layers
		(0 "F.Cu" signal "TOP")
		(4 "In1.Cu" signal "02_GND")
		(6 "In2.Cu" signal "03_SIG")
		(8 "In3.Cu" signal "04_SIG")
		(10 "In4.Cu" signal "05_GND")
		(12 "In5.Cu" signal "06_PWR1")
		(14 "In6.Cu" signal "07_SIG")
		(16 "In7.Cu" signal "08_SIG")
		(18 "In8.Cu" signal "09_GND")
		(2 "B.Cu" signal "BOTTOM")
		(9 "F.Adhes" user "F.Adhesive")
		(11 "B.Adhes" user "B.Adhesive")
		(13 "F.Paste" user "Package Geometry/Pastemask Top")
		(15 "B.Paste" user "Package Geometry/Pastemask Bottom")
		(5 "F.SilkS" user "Ref Des/Silkscreen Top")
		(7 "B.SilkS" user "Ref Des/Silkscreen Bottom")
		(1 "F.Mask" user "Board Geometry/Soldermask Top")
		(3 "B.Mask" user "Board Geometry/Soldermask Bottom")
		(17 "Dwgs.User" user "User.Drawings")
		(19 "Cmts.User" user "User.Comments")
		(21 "Eco1.User" user "User.Eco1")
		(23 "Eco2.User" user "User.Eco2")
		(25 "Edge.Cuts" user "Board Geometry/Outline")
		(27 "Margin" user)
		(31 "F.CrtYd" user "Package Geometry/Place Bound Top")
		(29 "B.CrtYd" user "Package Geometry/Place Bound Bottom")
		(35 "F.Fab" user "Ref Des/Assembly Top")
		(33 "B.Fab" user "Ref Des/Assembly Bottom")
		(45 "User.4" user "COMPVAL_TYPE_BOTTOM")
	)
	(footprint ""
		(layer "B.Cu")
		(at 35.8902 20.447 -90)
		(property "Reference" "C119"
			(at 0 0 90)
			(layer "B.SilkS")
			(hide yes)
			(effects
				(font
					(size 1.27 1.27)
				)
				(justify mirror)
			)
		)
		(property "Value" "0.1UF"
			(at 0.091846 0.2921 180)
			(unlocked yes)
			(layer "B.Fab")
			(hide yes)
			(effects
				(font
					(size 0.7874 0.5842)
					(thickness 0.2032)
				)
				(justify left mirror)
			)
		)
		(property "Device Type" "CAPC0073"
			(at 0.091846 0.2921 180)
			(unlocked yes)
			(layer "B.Fab")
			(hide yes)
			(effects
				(font
					(size 0.7874 0.5842)
					(thickness 0.2032)
				)
				(justify left mirror)
			)
		)
		(duplicate_pad_numbers_are_jumpers no)
		(fp_poly
			(pts
				(xy -0.635 1.0668) (xy -0.635 -1.0668) (xy 0.635 -1.0668) (xy 0.635 1.0668)
			)
			(stroke
				(width 0)
				(type default)
			)
			(fill no)
			(layer "B.CrtYd")
		)
		(fp_line
			(start -0.254 0.508)
			(end 0.254 0.508)
			(stroke
				(width 0.0254)
				(type default)
			)
			(layer "B.Fab")
		)
		(fp_line
			(start 0.254 0.508)
			(end 0.254 -0.508)
			(stroke
				(width 0.0254)
				(type default)
			)
			(layer "B.Fab")
		)
		(fp_line
			(start -0.254 -0.508)
			(end -0.254 0.508)
			(stroke
				(width 0.0254)
				(type default)
			)
			(layer "B.Fab")
		)
		(fp_line
			(start 0.254 -0.508)
			(end -0.254 -0.508)
			(stroke
				(width 0.0254)
				(type default)
			)
			(layer "B.Fab")
		)
		(pad "1" smd rect
			(at 0 -0.4191 90)
			(size 0.508 0.5334)
			(layers "B.Cu" "B.Mask" "B.Paste")
			(net "EXT_3.3V")
		)
		(pad "2" smd rect
			(at 0 0.4191 90)
			(size 0.508 0.5334)
			(layers "B.Cu" "B.Mask" "B.Paste")
			(net "GND")
		)
		(zone
			(layer "B.Cu")
			(hatch none 0.5)
			(connect_pads
				(clearance 0)
			)
			(min_thickness 0.25)
			(keepout
				(tracks not_allowed)
				(vias allowed)
				(pads allowed)
				(copperpour not_allowed)
				(footprints allowed)
			)
			(placement
				(enabled no)
				(sheetname "")
			)
			(fill
				(thermal_gap 0.5)
				(thermal_bridge_width 0.5)
				(island_removal_mode 0)
			)
			(polygon
				(pts
					(xy 35.9156 20.4216) (xy 35.8648 20.4216) (xy 35.8648 20.4724) (xy 35.9156 20.4724)
				)
			)
		)
	)
	(footprint ""
		(layer "B.Cu")
		(at 16.764 32.131)
		(property "Reference" "TP69"
			(at 1.87833 2.667 270)
			(unlocked yes)
			(layer "B.SilkS")
			(effects
				(font
					(size 0.7874 0.5842)
					(thickness 0.127)
				)
				(justify left mirror)
			)
		)
		(property "Value" "*"
			(at 0.4826 -0.14732 0)
			(unlocked yes)
			(layer "B.Fab")
			(hide yes)
			(effects
				(font
					(size 1.27 0.9652)
					(thickness 0.000001)
				)
				(justify left mirror)
			)
		)
		(property "Device Type" "TP_SMALL"
			(at 0.4826 -0.14732 0)
			(unlocked yes)
			(layer "B.Fab")
			(hide yes)
			(effects
				(font
					(size 1.27 0.9652)
					(thickness 0.000001)
				)
				(justify left mirror)
			)
		)
		(duplicate_pad_numbers_are_jumpers no)
		(fp_line
			(start -0.8636 -0.8636)
			(end 0.8636 -0.8636)
			(stroke
				(width 0.1524)
				(type default)
			)
			(layer "B.SilkS")
		)
		(fp_line
			(start -0.8636 0.8636)
			(end -0.8636 -0.8636)
			(stroke
				(width 0.1524)
				(type default)
			)
			(layer "B.SilkS")
		)
		(fp_line
			(start 0.8636 -0.8636)
			(end 0.8636 0.8636)
			(stroke
				(width 0.1524)
				(type default)
			)
			(layer "B.SilkS")
		)
		(fp_line
			(start 0.8636 0.8636)
			(end -0.8636 0.8636)
			(stroke
				(width 0.1524)
				(type default)
			)
			(layer "B.SilkS")
		)
		(fp_poly
			(pts
				(xy 0.635 -0.635) (xy 0.635 0.635) (xy -0.635 0.635) (xy -0.635 -0.635)
			)
			(stroke
				(width 0)
				(type default)
			)
			(fill no)
			(layer "B.CrtYd")
		)
		(pad "1" smd rect
			(at 0 0 180)
			(size 1.27 1.27)
			(layers "B.Cu" "B.Mask" "B.Paste")
			(net "GND")
		)
	)
	(footprint ""
		(layer "B.Cu")
		(at 83.450989 29.812996)
		(property "Reference" "V3_A-A11"
			(at 0 0 0)
			(layer "B.SilkS")
			(hide yes)
			(effects
				(font
					(size 1.27 1.27)
				)
				(justify mirror)
			)
		)
		(property "Value" ""
			(at 0 0 0)
			(layer "B.Fab")
			(effects
				(font
					(size 1.27 1.27)
				)
				(justify mirror)
			)
		)
		(duplicate_pad_numbers_are_jumpers no)
		(pad "1" thru_hole circle
			(at 0 0 180)
			(size 0.4572 0.4572)
			(drill 0.20574)
			(layers "*.Cu" "*.Mask")
			(remove_unused_layers no)
			(net "DDR0_32A_A11")
			(clearance 0.1143)
			(thermal_gap 0.1143)
		)
	)
	(footprint ""
		(layer "B.Cu")
		(at 61.736986 16.042005 -90)
		(property "Reference" "C196"
			(at 0 0 90)
			(layer "B.SilkS")
			(hide yes)
			(effects
				(font
					(size 1.27 1.27)
				)
				(justify mirror)
			)
		)
		(property "Value" ""
			(at 0 0 90)
			(layer "B.Fab")
			(effects
				(font
					(size 1.27 1.27)
				)
				(justify mirror)
			)
		)
		(duplicate_pad_numbers_are_jumpers no)
		(fp_circle
			(center 0 0)
			(end 0 -0.104648)
			(stroke
				(width 0.1016)
				(type default)
			)
			(fill no)
			(layer "B.SilkS")
		)
		(fp_poly
			(pts
				(xy 0.381 -0.889) (xy 0.381 0.889) (xy -0.381 0.889) (xy -0.381 -0.889)
			)
			(stroke
				(width 0)
				(type default)
			)
			(fill no)
			(layer "B.CrtYd")
		)
		(fp_line
			(start -0.508 1.016)
			(end 0.508 1.016)
			(stroke
				(width 0.0254)
				(type default)
			)
			(layer "B.Fab")
		)
		(fp_line
			(start 0.508 1.016)
			(end 0.508 -1.016)
			(stroke
				(width 0.0254)
				(type default)
			)
			(layer "B.Fab")
		)
		(fp_line
			(start -0.508 -1.016)
			(end -0.508 1.016)
			(stroke
				(width 0.0254)
				(type default)
			)
			(layer "B.Fab")
		)
		(fp_line
			(start 0.254 -1.016)
			(end -0.508 -1.016)
			(stroke
				(width 0.0254)
				(type default)
			)
			(layer "B.Fab")
		)
		(fp_line
			(start 0.508 -1.016)
			(end 0.254 -1.016)
			(stroke
				(width 0.0254)
				(type default)
			)
			(layer "B.Fab")
		)
		(pad "1" smd custom
			(at 0 -0.500126 90)
			(size 0.127 0.127)
			(layers "B.Cu" "B.Mask" "B.Paste")
			(net "DDR0_32A_VREF")
			(options
				(clearance outline)
				(anchor circle)
			)
			(primitives
				(gr_poly
					(pts
						(xy -0.1778 0.254) (xy 0.1778 0.254) (xy 0.254 0.1778) (xy 0.254 -0.1778) (xy 0.1778 -0.254) (xy -0.1778 -0.254)
						(xy -0.254 -0.1778) (xy -0.254 0.1778)
					)
					(width 0)
					(fill yes)
				)
			)
		)
		(pad "2" smd custom
			(at 0 0.500126 90)
			(size 0.127 0.127)
			(layers "B.Cu" "B.Mask" "B.Paste")
			(net "GND")
			(options
				(clearance outline)
				(anchor circle)
			)
			(primitives
				(gr_poly
					(pts
						(xy -0.1778 0.254) (xy 0.1778 0.254) (xy 0.254 0.1778) (xy 0.254 -0.1778) (xy 0.1778 -0.254) (xy -0.1778 -0.254)
						(xy -0.254 -0.1778) (xy -0.254 0.1778)
					)
					(width 0)
					(fill yes)
				)
			)
		)
	)
	(footprint ""
		(layer "B.Cu")
		(at 40.894 44.831)
		(property "Reference" "TP24"
			(at 3.302 -1.75133 0)
			(unlocked yes)
			(layer "B.SilkS")
			(effects
				(font
					(size 0.7874 0.5842)
					(thickness 0.127)
				)
				(justify left mirror)
			)
		)
		(property "Value" "*"
			(at 0.4826 -0.14732 0)
			(unlocked yes)
			(layer "B.Fab")
			(hide yes)
			(effects
				(font
					(size 1.27 0.9652)
					(thickness 0.000001)
				)
				(justify left mirror)
			)
		)
		(property "Device Type" "TP_SMALL"
			(at 0.4826 -0.14732 0)
			(unlocked yes)
			(layer "B.Fab")
			(hide yes)
			(effects
				(font
					(size 1.27 0.9652)
					(thickness 0.000001)
				)
				(justify left mirror)
			)
		)
		(duplicate_pad_numbers_are_jumpers no)
		(fp_line
			(start -0.8636 -0.8636)
			(end 0.8636 -0.8636)
			(stroke
				(width 0.1524)
				(type default)
			)
			(layer "B.SilkS")
		)
		(fp_line
			(start -0.8636 0.8636)
			(end -0.8636 -0.8636)
			(stroke
				(width 0.1524)
				(type default)
			)
			(layer "B.SilkS")
		)
		(fp_line
			(start 0.8636 -0.8636)
			(end 0.8636 0.8636)
			(stroke
				(width 0.1524)
				(type default)
			)
			(layer "B.SilkS")
		)
		(fp_line
			(start 0.8636 0.8636)
			(end -0.8636 0.8636)
			(stroke
				(width 0.1524)
				(type default)
			)
			(layer "B.SilkS")
		)
		(fp_poly
			(pts
				(xy 0.635 -0.635) (xy 0.635 0.635) (xy -0.635 0.635) (xy -0.635 -0.635)
			)
			(stroke
				(width 0)
				(type default)
			)
			(fill no)
			(layer "B.CrtYd")
		)
		(pad "1" smd rect
			(at 0 0 180)
			(size 1.27 1.27)
			(layers "B.Cu" "B.Mask" "B.Paste")
			(net "NFP_CFG_SPI_FLASH_HOLD_L")
		)
	)
	(footprint ""
		(layer "B.Cu")
		(at 56.007 41.91)
		(property "Reference" "C17"
			(at 1.143 -1.87833 0)
			(unlocked yes)
			(layer "B.SilkS")
			(effects
				(font
					(size 0.7874 0.5842)
					(thickness 0.127)
				)
				(justify left mirror)
			)
		)
		(property "Value" "22UF"
			(at 0.148158 1.7526 270)
			(unlocked yes)
			(layer "B.Fab")
			(hide yes)
			(effects
				(font
					(size 1.27 0.9652)
					(thickness 0.000001)
				)
				(justify left mirror)
			)
		)
		(property "Device Type" "CAPC0063"
			(at 0.148158 1.7526 270)
			(unlocked yes)
			(layer "B.Fab")
			(hide yes)
			(effects
				(font
					(size 1.27 0.9652)
					(thickness 0.000001)
				)
				(justify left mirror)
			)
		)
		(duplicate_pad_numbers_are_jumpers no)
		(fp_circle
			(center 0 0)
			(end 0.127 0)
			(stroke
				(width 0.2032)
				(type default)
			)
			(fill no)
			(layer "B.SilkS")
		)
		(fp_poly
			(pts
				(xy -0.7874 -1.6637) (xy 0.7874 -1.6637) (xy 0.7874 1.6637) (xy -0.7874 1.6637)
			)
			(stroke
				(width 0)
				(type default)
			)
			(fill no)
			(layer "B.CrtYd")
		)
		(fp_line
			(start -0.4064 -0.7874)
			(end -0.4064 0.8128)
			(stroke
				(width 0.0254)
				(type default)
			)
			(layer "B.Fab")
		)
		(fp_line
			(start -0.4064 0.8128)
			(end 0.4064 0.8128)
			(stroke
				(width 0.0254)
				(type default)
			)
			(layer "B.Fab")
		)
		(fp_line
			(start 0.4064 -0.7874)
			(end -0.4064 -0.7874)
			(stroke
				(width 0.0254)
				(type default)
			)
			(layer "B.Fab")
		)
		(fp_line
			(start 0.4064 0.8128)
			(end 0.4064 -0.7874)
			(stroke
				(width 0.0254)
				(type default)
			)
			(layer "B.Fab")
		)
		(pad "1" smd rect
			(at 0 -0.8001 180)
			(size 0.8636 0.9652)
			(layers "B.Cu" "B.Mask" "B.Paste")
			(net "VDD_CORE")
		)
		(pad "2" smd rect
			(at 0 0.8001 180)
			(size 0.8636 0.9652)
			(layers "B.Cu" "B.Mask" "B.Paste")
			(net "GND")
		)
		(zone
			(layer "B.Cu")
			(hatch none 0.5)
			(connect_pads
				(clearance 0)
			)
			(min_thickness 0.25)
			(keepout
				(tracks not_allowed)
				(vias allowed)
				(pads allowed)
				(copperpour not_allowed)
				(footprints allowed)
			)
			(placement
				(enabled no)
				(sheetname "")
			)
			(fill
				(thermal_gap 0.5)
				(thermal_bridge_width 0.5)
				(island_removal_mode 0)
			)
			(polygon
				(pts
					(xy 56.0705 41.656) (xy 55.9435 41.656) (xy 55.9435 42.164) (xy 56.0705 42.164)
				)
			)
		)
	)
	(footprint ""
		(layer "B.Cu")
		(at 81.850992 2.699004)
		(property "Reference" "V1_A-A00"
			(at 0 0 0)
			(layer "B.SilkS")
			(hide yes)
			(effects
				(font
					(size 1.27 1.27)
				)
				(justify mirror)
			)
		)
		(property "Value" ""
			(at 0 0 0)
			(layer "B.Fab")
			(effects
				(font
					(size 1.27 1.27)
				)
				(justify mirror)
			)
		)
		(duplicate_pad_numbers_are_jumpers no)
		(pad "1" thru_hole circle
			(at 0 0 180)
			(size 0.4572 0.4572)
			(drill 0.20574)
			(layers "*.Cu" "*.Mask")
			(remove_unused_layers no)
			(net "DDR0_32A_A0")
			(clearance 0.1143)
			(thermal_gap 0.1143)
		)
	)
	(footprint ""
		(layer "B.Cu")
		(at 60.236989 9.542018)
		(property "Reference" "C37"
			(at 0 0 0)
			(layer "B.SilkS")
			(hide yes)
			(effects
				(font
					(size 1.27 1.27)
				)
				(justify mirror)
			)
		)
		(property "Value" ""
			(at 0 0 0)
			(layer "B.Fab")
			(effects
				(font
					(size 1.27 1.27)
				)
				(justify mirror)
			)
		)
		(duplicate_pad_numbers_are_jumpers no)
		(fp_circle
			(center 0 0)
			(end 0.104648 0)
			(stroke
				(width 0.1016)
				(type default)
			)
			(fill no)
			(layer "B.SilkS")
		)
		(fp_poly
			(pts
				(xy 0.381 -0.889) (xy 0.381 0.889) (xy -0.381 0.889) (xy -0.381 -0.889)
			)
			(stroke
				(width 0)
				(type default)
			)
			(fill no)
			(layer "B.CrtYd")
		)
		(fp_line
			(start -0.508 -1.016)
			(end -0.508 1.016)
			(stroke
				(width 0.0254)
				(type default)
			)
			(layer "B.Fab")
		)
		(fp_line
			(start -0.508 1.016)
			(end 0.508 1.016)
			(stroke
				(width 0.0254)
				(type default)
			)
			(layer "B.Fab")
		)
		(fp_line
			(start 0.254 -1.016)
			(end -0.508 -1.016)
			(stroke
				(width 0.0254)
				(type default)
			)
			(layer "B.Fab")
		)
		(fp_line
			(start 0.508 -1.016)
			(end 0.254 -1.016)
			(stroke
				(width 0.0254)
				(type default)
			)
			(layer "B.Fab")
		)
		(fp_line
			(start 0.508 1.016)
			(end 0.508 -1.016)
			(stroke
				(width 0.0254)
				(type default)
			)
			(layer "B.Fab")
		)
		(pad "1" smd custom
			(at 0 -0.500126 180)
			(size 0.127 0.127)
			(layers "B.Cu" "B.Mask" "B.Paste")
			(net "VDDA_PCIE0")
			(options
				(clearance outline)
				(anchor circle)
			)
			(primitives
				(gr_poly
					(pts
						(xy -0.1778 0.254) (xy 0.1778 0.254) (xy 0.254 0.1778) (xy 0.254 -0.1778) (xy 0.1778 -0.254) (xy -0.1778 -0.254)
						(xy -0.254 -0.1778) (xy -0.254 0.1778)
					)
					(width 0)
					(fill yes)
				)
			)
		)
		(pad "2" smd custom
			(at 0 0.500126 180)
			(size 0.127 0.127)
			(layers "B.Cu" "B.Mask" "B.Paste")
			(net "GND")
			(options
				(clearance outline)
				(anchor circle)
			)
			(primitives
				(gr_poly
					(pts
						(xy -0.1778 0.254) (xy 0.1778 0.254) (xy 0.254 0.1778) (xy 0.254 -0.1778) (xy 0.1778 -0.254) (xy -0.1778 -0.254)
						(xy -0.254 -0.1778) (xy -0.254 0.1778)
					)
					(width 0)
					(fill yes)
				)
			)
		)
	)
	(footprint ""
		(layer "B.Cu")
		(at 27.305 19.2024 -90)
		(property "Reference" "C120"
			(at -1.31953 -0.762 0)
			(unlocked yes)
			(layer "B.SilkS")
			(effects
				(font
					(size 0.7874 0.5842)
					(thickness 0.127)
				)
				(justify left mirror)
			)
		)
		(property "Value" "0.1UF"
			(at 0.091846 0.2921 180)
			(unlocked yes)
			(layer "B.Fab")
			(hide yes)
			(effects
				(font
					(size 0.7874 0.5842)
					(thickness 0.2032)
				)
				(justify left mirror)
			)
		)
		(property "Device Type" "CAPC0073"
			(at 0.091846 0.2921 180)
			(unlocked yes)
			(layer "B.Fab")
			(hide yes)
			(effects
				(font
					(size 0.7874 0.5842)
					(thickness 0.2032)
				)
				(justify left mirror)
			)
		)
		(duplicate_pad_numbers_are_jumpers no)
		(fp_poly
			(pts
				(xy -0.635 1.0668) (xy -0.635 -1.0668) (xy 0.635 -1.0668) (xy 0.635 1.0668)
			)
			(stroke
				(width 0)
				(type default)
			)
			(fill no)
			(layer "B.CrtYd")
		)
		(fp_line
			(start -0.254 0.508)
			(end 0.254 0.508)
			(stroke
				(width 0.0254)
				(type default)
			)
			(layer "B.Fab")
		)
		(fp_line
			(start 0.254 0.508)
			(end 0.254 -0.508)
			(stroke
				(width 0.0254)
				(type default)
			)
			(layer "B.Fab")
		)
		(fp_line
			(start -0.254 -0.508)
			(end -0.254 0.508)
			(stroke
				(width 0.0254)
				(type default)
			)
			(layer "B.Fab")
		)
		(fp_line
			(start 0.254 -0.508)
			(end -0.254 -0.508)
			(stroke
				(width 0.0254)
				(type default)
			)
			(layer "B.Fab")
		)
		(pad "1" smd rect
			(at 0 -0.4191 90)
			(size 0.508 0.5334)
			(layers "B.Cu" "B.Mask" "B.Paste")
			(net "EXT_3.3V")
		)
		(pad "2" smd rect
			(at 0 0.4191 90)
			(size 0.508 0.5334)
			(layers "B.Cu" "B.Mask" "B.Paste")
			(net "GND")
		)
		(zone
			(layer "B.Cu")
			(hatch none 0.5)
			(connect_pads
				(clearance 0)
			)
			(min_thickness 0.25)
			(keepout
				(tracks not_allowed)
				(vias allowed)
				(pads allowed)
				(copperpour not_allowed)
				(footprints allowed)
			)
			(placement
				(enabled no)
				(sheetname "")
			)
			(fill
				(thermal_gap 0.5)
				(thermal_bridge_width 0.5)
				(island_removal_mode 0)
			)
			(polygon
				(pts
					(xy 27.3304 19.177) (xy 27.2796 19.177) (xy 27.2796 19.2278) (xy 27.3304 19.2278)
				)
			)
		)
	)
	(footprint ""
		(layer "B.Cu")
		(at 77.343 43.688)
		(property "Reference" "C137"
			(at 0.311988 4.4958 270)
			(unlocked yes)
			(layer "B.SilkS")
			(effects
				(font
					(size 0.7874 0.5842)
					(thickness 0.127)
				)
				(justify left mirror)
			)
		)
		(property "Value" "10UF"
			(at 0.148158 1.7526 270)
			(unlocked yes)
			(layer "B.Fab")
			(hide yes)
			(effects
				(font
					(size 1.27 0.9652)
					(thickness 0.000001)
				)
				(justify left mirror)
			)
		)
		(property "Device Type" "CAPC0058"
			(at 0.148158 1.7526 270)
			(unlocked yes)
			(layer "B.Fab")
			(hide yes)
			(effects
				(font
					(size 1.27 0.9652)
					(thickness 0.000001)
				)
				(justify left mirror)
			)
		)
		(duplicate_pad_numbers_are_jumpers no)
		(fp_circle
			(center 0 0)
			(end 0.127 0)
			(stroke
				(width 0.2032)
				(type default)
			)
			(fill no)
			(layer "B.SilkS")
		)
		(fp_poly
			(pts
				(xy -0.7874 -1.6637) (xy 0.7874 -1.6637) (xy 0.7874 1.6637) (xy -0.7874 1.6637)
			)
			(stroke
				(width 0)
				(type default)
			)
			(fill no)
			(layer "B.CrtYd")
		)
		(fp_line
			(start -0.4064 -0.7874)
			(end -0.4064 0.8128)
			(stroke
				(width 0.0254)
				(type default)
			)
			(layer "B.Fab")
		)
		(fp_line
			(start -0.4064 0.8128)
			(end 0.4064 0.8128)
			(stroke
				(width 0.0254)
				(type default)
			)
			(layer "B.Fab")
		)
		(fp_line
			(start 0.4064 -0.7874)
			(end -0.4064 -0.7874)
			(stroke
				(width 0.0254)
				(type default)
			)
			(layer "B.Fab")
		)
		(fp_line
			(start 0.4064 0.8128)
			(end 0.4064 -0.7874)
			(stroke
				(width 0.0254)
				(type default)
			)
			(layer "B.Fab")
		)
		(pad "1" smd rect
			(at 0 -0.8001 180)
			(size 0.8636 0.9652)
			(layers "B.Cu" "B.Mask" "B.Paste")
			(net "DDR_VTT")
		)
		(pad "2" smd rect
			(at 0 0.8001 180)
			(size 0.8636 0.9652)
			(layers "B.Cu" "B.Mask" "B.Paste")
			(net "GND")
		)
		(zone
			(layer "B.Cu")
			(hatch none 0.5)
			(connect_pads
				(clearance 0)
			)
			(min_thickness 0.25)
			(keepout
				(tracks not_allowed)
				(vias allowed)
				(pads allowed)
				(copperpour not_allowed)
				(footprints allowed)
			)
			(placement
				(enabled no)
				(sheetname "")
			)
			(fill
				(thermal_gap 0.5)
				(thermal_bridge_width 0.5)
				(island_removal_mode 0)
			)
			(polygon
				(pts
					(xy 77.4065 43.434) (xy 77.2795 43.434) (xy 77.2795 43.942) (xy 77.4065 43.942)
				)
			)
		)
	)
)
